FILE_TYPE=LIBRARY_PARTS;
primitive 'SCONN288_H44441004','SCONN288_H44441004_PIP';
  pin
    '12V'<1>:
      PIN_NUMBER='(0,0,0,1)';
      PINUSE='POWER';
      NO_LOAD_CHECK='Both';
      NO_IO_CHECK='Both';
      NO_ASSERT_CHECK='TRUE';
      NO_DIR_CHECK='TRUE';
      ALLOW_CONNECT='TRUE';
    '12V'<0>:
      PIN_NUMBER='(0,0,0,145)';
      PINUSE='POWER';
      NO_LOAD_CHECK='Both';
      NO_IO_CHECK='Both';
      NO_ASSERT_CHECK='TRUE';
      NO_DIR_CHECK='TRUE';
      ALLOW_CONNECT='TRUE';
    'A0':
      PIN_NUMBER='(79,0,0,0)';
      BIDIRECTIONAL='TRUE';
      INPUT_LOAD='(-0.01,0.01)';
      OUTPUT_LOAD='(1.0,-1.0)';
    'A1':
      PIN_NUMBER='(72,0,0,0)';
      BIDIRECTIONAL='TRUE';
      INPUT_LOAD='(-0.01,0.01)';
      OUTPUT_LOAD='(1.0,-1.0)';
    'A10':
      PIN_NUMBER='(225,0,0,0)';
      BIDIRECTIONAL='TRUE';
      INPUT_LOAD='(-0.01,0.01)';
      OUTPUT_LOAD='(1.0,-1.0)';
    'A11':
      PIN_NUMBER='(210,0,0,0)';
      BIDIRECTIONAL='TRUE';
      INPUT_LOAD='(-0.01,0.01)';
      OUTPUT_LOAD='(1.0,-1.0)';
    'A12':
      PIN_NUMBER='(65,0,0,0)';
      BIDIRECTIONAL='TRUE';
      INPUT_LOAD='(-0.01,0.01)';
      OUTPUT_LOAD='(1.0,-1.0)';
    'A13':
      PIN_NUMBER='(232,0,0,0)';
      BIDIRECTIONAL='TRUE';
      INPUT_LOAD='(-0.01,0.01)';
      OUTPUT_LOAD='(1.0,-1.0)';
    'A14_WE_N':
      PIN_NUMBER='(228,0,0,0)';
      BIDIRECTIONAL='TRUE';
      INPUT_LOAD='(-0.01,0.01)';
      OUTPUT_LOAD='(1.0,-1.0)';
    'A15_CAS_N':
      PIN_NUMBER='(86,0,0,0)';
      BIDIRECTIONAL='TRUE';
      INPUT_LOAD='(-0.01,0.01)';
      OUTPUT_LOAD='(1.0,-1.0)';
    'A16_RAS_N':
      PIN_NUMBER='(82,0,0,0)';
      BIDIRECTIONAL='TRUE';
      INPUT_LOAD='(-0.01,0.01)';
      OUTPUT_LOAD='(1.0,-1.0)';
    'A17':
      PIN_NUMBER='(234,0,0,0)';
      BIDIRECTIONAL='TRUE';
      INPUT_LOAD='(-0.01,0.01)';
      OUTPUT_LOAD='(1.0,-1.0)';
    'A2':
      PIN_NUMBER='(216,0,0,0)';
      BIDIRECTIONAL='TRUE';
      INPUT_LOAD='(-0.01,0.01)';
      OUTPUT_LOAD='(1.0,-1.0)';
    'A3':
      PIN_NUMBER='(71,0,0,0)';
      BIDIRECTIONAL='TRUE';
      INPUT_LOAD='(-0.01,0.01)';
      OUTPUT_LOAD='(1.0,-1.0)';
    'A4':
      PIN_NUMBER='(214,0,0,0)';
      BIDIRECTIONAL='TRUE';
      INPUT_LOAD='(-0.01,0.01)';
      OUTPUT_LOAD='(1.0,-1.0)';
    'A5':
      PIN_NUMBER='(213,0,0,0)';
      BIDIRECTIONAL='TRUE';
      INPUT_LOAD='(-0.01,0.01)';
      OUTPUT_LOAD='(1.0,-1.0)';
    'A6':
      PIN_NUMBER='(69,0,0,0)';
      BIDIRECTIONAL='TRUE';
      INPUT_LOAD='(-0.01,0.01)';
      OUTPUT_LOAD='(1.0,-1.0)';
    'A7':
      PIN_NUMBER='(211,0,0,0)';
      BIDIRECTIONAL='TRUE';
      INPUT_LOAD='(-0.01,0.01)';
      OUTPUT_LOAD='(1.0,-1.0)';
    'A8':
      PIN_NUMBER='(68,0,0,0)';
      BIDIRECTIONAL='TRUE';
      INPUT_LOAD='(-0.01,0.01)';
      OUTPUT_LOAD='(1.0,-1.0)';
    'A9':
      PIN_NUMBER='(66,0,0,0)';
      BIDIRECTIONAL='TRUE';
      INPUT_LOAD='(-0.01,0.01)';
      OUTPUT_LOAD='(1.0,-1.0)';
    'ACT_N':
      PIN_NUMBER='(62,0,0,0)';
      BIDIRECTIONAL='TRUE';
      INPUT_LOAD='(-0.01,0.01)';
      OUTPUT_LOAD='(1.0,-1.0)';
    'ALERT_N':
      PIN_NUMBER='(208,0,0,0)';
      BIDIRECTIONAL='TRUE';
      INPUT_LOAD='(-0.01,0.01)';
      OUTPUT_LOAD='(1.0,-1.0)';
    'BA'<1>:
      PIN_NUMBER='(224,0,0,0)';
      BIDIRECTIONAL='TRUE';
      INPUT_LOAD='(-0.01,0.01)';
      OUTPUT_LOAD='(1.0,-1.0)';
    'BA'<0>:
      PIN_NUMBER='(81,0,0,0)';
      BIDIRECTIONAL='TRUE';
      INPUT_LOAD='(-0.01,0.01)';
      OUTPUT_LOAD='(1.0,-1.0)';
    'BG'<1>:
      PIN_NUMBER='(207,0,0,0)';
      BIDIRECTIONAL='TRUE';
      INPUT_LOAD='(-0.01,0.01)';
      OUTPUT_LOAD='(1.0,-1.0)';
    'BG'<0>:
      PIN_NUMBER='(63,0,0,0)';
      BIDIRECTIONAL='TRUE';
      INPUT_LOAD='(-0.01,0.01)';
      OUTPUT_LOAD='(1.0,-1.0)';
    'C'<2>:
      PIN_NUMBER='(235,0,0,0)';
      BIDIRECTIONAL='TRUE';
      INPUT_LOAD='(-0.01,0.01)';
      OUTPUT_LOAD='(1.0,-1.0)';
    'CB'<7>:
      PIN_NUMBER='(199,0,0,0)';
      BIDIRECTIONAL='TRUE';
      INPUT_LOAD='(-0.01,0.01)';
      OUTPUT_LOAD='(1.0,-1.0)';
    'CB'<6>:
      PIN_NUMBER='(54,0,0,0)';
      BIDIRECTIONAL='TRUE';
      INPUT_LOAD='(-0.01,0.01)';
      OUTPUT_LOAD='(1.0,-1.0)';
    'CB'<5>:
      PIN_NUMBER='(192,0,0,0)';
      BIDIRECTIONAL='TRUE';
      INPUT_LOAD='(-0.01,0.01)';
      OUTPUT_LOAD='(1.0,-1.0)';
    'CB'<4>:
      PIN_NUMBER='(47,0,0,0)';
      BIDIRECTIONAL='TRUE';
      INPUT_LOAD='(-0.01,0.01)';
      OUTPUT_LOAD='(1.0,-1.0)';
    'CB'<3>:
      PIN_NUMBER='(201,0,0,0)';
      BIDIRECTIONAL='TRUE';
      INPUT_LOAD='(-0.01,0.01)';
      OUTPUT_LOAD='(1.0,-1.0)';
    'CB'<2>:
      PIN_NUMBER='(56,0,0,0)';
      BIDIRECTIONAL='TRUE';
      INPUT_LOAD='(-0.01,0.01)';
      OUTPUT_LOAD='(1.0,-1.0)';
    'CB'<1>:
      PIN_NUMBER='(194,0,0,0)';
      BIDIRECTIONAL='TRUE';
      INPUT_LOAD='(-0.01,0.01)';
      OUTPUT_LOAD='(1.0,-1.0)';
    'CB'<0>:
      PIN_NUMBER='(49,0,0,0)';
      BIDIRECTIONAL='TRUE';
      INPUT_LOAD='(-0.01,0.01)';
      OUTPUT_LOAD='(1.0,-1.0)';
    'CK0N':
      PIN_NUMBER='(75,0,0,0)';
      BIDIRECTIONAL='TRUE';
      INPUT_LOAD='(-0.01,0.01)';
      OUTPUT_LOAD='(1.0,-1.0)';
    'CK0P':
      PIN_NUMBER='(74,0,0,0)';
      BIDIRECTIONAL='TRUE';
      INPUT_LOAD='(-0.01,0.01)';
      OUTPUT_LOAD='(1.0,-1.0)';
    'CK1N':
      PIN_NUMBER='(219,0,0,0)';
      BIDIRECTIONAL='TRUE';
      INPUT_LOAD='(-0.01,0.01)';
      OUTPUT_LOAD='(1.0,-1.0)';
    'CK1P':
      PIN_NUMBER='(218,0,0,0)';
      BIDIRECTIONAL='TRUE';
      INPUT_LOAD='(-0.01,0.01)';
      OUTPUT_LOAD='(1.0,-1.0)';
    'CKE'<1>:
      PIN_NUMBER='(203,0,0,0)';
      BIDIRECTIONAL='TRUE';
      INPUT_LOAD='(-0.01,0.01)';
      OUTPUT_LOAD='(1.0,-1.0)';
    'CKE'<0>:
      PIN_NUMBER='(60,0,0,0)';
      BIDIRECTIONAL='TRUE';
      INPUT_LOAD='(-0.01,0.01)';
      OUTPUT_LOAD='(1.0,-1.0)';
    'DQ'<63>:
      PIN_NUMBER='(280,0,0,0)';
      BIDIRECTIONAL='TRUE';
      INPUT_LOAD='(-0.01,0.01)';
      OUTPUT_LOAD='(1.0,-1.0)';
    'DQ'<62>:
      PIN_NUMBER='(135,0,0,0)';
      BIDIRECTIONAL='TRUE';
      INPUT_LOAD='(-0.01,0.01)';
      OUTPUT_LOAD='(1.0,-1.0)';
    'DQ'<61>:
      PIN_NUMBER='(273,0,0,0)';
      BIDIRECTIONAL='TRUE';
      INPUT_LOAD='(-0.01,0.01)';
      OUTPUT_LOAD='(1.0,-1.0)';
    'DQ'<60>:
      PIN_NUMBER='(128,0,0,0)';
      BIDIRECTIONAL='TRUE';
      INPUT_LOAD='(-0.01,0.01)';
      OUTPUT_LOAD='(1.0,-1.0)';
    'DQ'<59>:
      PIN_NUMBER='(282,0,0,0)';
      BIDIRECTIONAL='TRUE';
      INPUT_LOAD='(-0.01,0.01)';
      OUTPUT_LOAD='(1.0,-1.0)';
    'DQ'<58>:
      PIN_NUMBER='(137,0,0,0)';
      BIDIRECTIONAL='TRUE';
      INPUT_LOAD='(-0.01,0.01)';
      OUTPUT_LOAD='(1.0,-1.0)';
    'DQ'<57>:
      PIN_NUMBER='(275,0,0,0)';
      BIDIRECTIONAL='TRUE';
      INPUT_LOAD='(-0.01,0.01)';
      OUTPUT_LOAD='(1.0,-1.0)';
    'DQ'<56>:
      PIN_NUMBER='(130,0,0,0)';
      BIDIRECTIONAL='TRUE';
      INPUT_LOAD='(-0.01,0.01)';
      OUTPUT_LOAD='(1.0,-1.0)';
    'DQ'<55>:
      PIN_NUMBER='(269,0,0,0)';
      BIDIRECTIONAL='TRUE';
      INPUT_LOAD='(-0.01,0.01)';
      OUTPUT_LOAD='(1.0,-1.0)';
    'DQ'<54>:
      PIN_NUMBER='(124,0,0,0)';
      BIDIRECTIONAL='TRUE';
      INPUT_LOAD='(-0.01,0.01)';
      OUTPUT_LOAD='(1.0,-1.0)';
    'DQ'<53>:
      PIN_NUMBER='(262,0,0,0)';
      BIDIRECTIONAL='TRUE';
      INPUT_LOAD='(-0.01,0.01)';
      OUTPUT_LOAD='(1.0,-1.0)';
    'DQ'<52>:
      PIN_NUMBER='(117,0,0,0)';
      BIDIRECTIONAL='TRUE';
      INPUT_LOAD='(-0.01,0.01)';
      OUTPUT_LOAD='(1.0,-1.0)';
    'DQ'<51>:
      PIN_NUMBER='(271,0,0,0)';
      BIDIRECTIONAL='TRUE';
      INPUT_LOAD='(-0.01,0.01)';
      OUTPUT_LOAD='(1.0,-1.0)';
    'DQ'<50>:
      PIN_NUMBER='(126,0,0,0)';
      BIDIRECTIONAL='TRUE';
      INPUT_LOAD='(-0.01,0.01)';
      OUTPUT_LOAD='(1.0,-1.0)';
    'DQ'<49>:
      PIN_NUMBER='(264,0,0,0)';
      BIDIRECTIONAL='TRUE';
      INPUT_LOAD='(-0.01,0.01)';
      OUTPUT_LOAD='(1.0,-1.0)';
    'DQ'<48>:
      PIN_NUMBER='(119,0,0,0)';
      BIDIRECTIONAL='TRUE';
      INPUT_LOAD='(-0.01,0.01)';
      OUTPUT_LOAD='(1.0,-1.0)';
    'DQ'<47>:
      PIN_NUMBER='(258,0,0,0)';
      BIDIRECTIONAL='TRUE';
      INPUT_LOAD='(-0.01,0.01)';
      OUTPUT_LOAD='(1.0,-1.0)';
    'DQ'<46>:
      PIN_NUMBER='(113,0,0,0)';
      BIDIRECTIONAL='TRUE';
      INPUT_LOAD='(-0.01,0.01)';
      OUTPUT_LOAD='(1.0,-1.0)';
    'DQ'<45>:
      PIN_NUMBER='(251,0,0,0)';
      BIDIRECTIONAL='TRUE';
      INPUT_LOAD='(-0.01,0.01)';
      OUTPUT_LOAD='(1.0,-1.0)';
    'DQ'<44>:
      PIN_NUMBER='(106,0,0,0)';
      BIDIRECTIONAL='TRUE';
      INPUT_LOAD='(-0.01,0.01)';
      OUTPUT_LOAD='(1.0,-1.0)';
    'DQ'<43>:
      PIN_NUMBER='(260,0,0,0)';
      BIDIRECTIONAL='TRUE';
      INPUT_LOAD='(-0.01,0.01)';
      OUTPUT_LOAD='(1.0,-1.0)';
    'DQ'<42>:
      PIN_NUMBER='(115,0,0,0)';
      BIDIRECTIONAL='TRUE';
      INPUT_LOAD='(-0.01,0.01)';
      OUTPUT_LOAD='(1.0,-1.0)';
    'DQ'<41>:
      PIN_NUMBER='(253,0,0,0)';
      BIDIRECTIONAL='TRUE';
      INPUT_LOAD='(-0.01,0.01)';
      OUTPUT_LOAD='(1.0,-1.0)';
    'DQ'<40>:
      PIN_NUMBER='(108,0,0,0)';
      BIDIRECTIONAL='TRUE';
      INPUT_LOAD='(-0.01,0.01)';
      OUTPUT_LOAD='(1.0,-1.0)';
    'DQ'<39>:
      PIN_NUMBER='(247,0,0,0)';
      BIDIRECTIONAL='TRUE';
      INPUT_LOAD='(-0.01,0.01)';
      OUTPUT_LOAD='(1.0,-1.0)';
    'DQ'<38>:
      PIN_NUMBER='(102,0,0,0)';
      BIDIRECTIONAL='TRUE';
      INPUT_LOAD='(-0.01,0.01)';
      OUTPUT_LOAD='(1.0,-1.0)';
    'DQ'<37>:
      PIN_NUMBER='(240,0,0,0)';
      BIDIRECTIONAL='TRUE';
      INPUT_LOAD='(-0.01,0.01)';
      OUTPUT_LOAD='(1.0,-1.0)';
    'DQ'<36>:
      PIN_NUMBER='(95,0,0,0)';
      BIDIRECTIONAL='TRUE';
      INPUT_LOAD='(-0.01,0.01)';
      OUTPUT_LOAD='(1.0,-1.0)';
    'DQ'<35>:
      PIN_NUMBER='(249,0,0,0)';
      BIDIRECTIONAL='TRUE';
      INPUT_LOAD='(-0.01,0.01)';
      OUTPUT_LOAD='(1.0,-1.0)';
    'DQ'<34>:
      PIN_NUMBER='(104,0,0,0)';
      BIDIRECTIONAL='TRUE';
      INPUT_LOAD='(-0.01,0.01)';
      OUTPUT_LOAD='(1.0,-1.0)';
    'DQ'<33>:
      PIN_NUMBER='(242,0,0,0)';
      BIDIRECTIONAL='TRUE';
      INPUT_LOAD='(-0.01,0.01)';
      OUTPUT_LOAD='(1.0,-1.0)';
    'DQ'<32>:
      PIN_NUMBER='(97,0,0,0)';
      BIDIRECTIONAL='TRUE';
      INPUT_LOAD='(-0.01,0.01)';
      OUTPUT_LOAD='(1.0,-1.0)';
    'DQ'<31>:
      PIN_NUMBER='(188,0,0,0)';
      BIDIRECTIONAL='TRUE';
      INPUT_LOAD='(-0.01,0.01)';
      OUTPUT_LOAD='(1.0,-1.0)';
    'DQ'<30>:
      PIN_NUMBER='(43,0,0,0)';
      BIDIRECTIONAL='TRUE';
      INPUT_LOAD='(-0.01,0.01)';
      OUTPUT_LOAD='(1.0,-1.0)';
    'DQ'<29>:
      PIN_NUMBER='(181,0,0,0)';
      BIDIRECTIONAL='TRUE';
      INPUT_LOAD='(-0.01,0.01)';
      OUTPUT_LOAD='(1.0,-1.0)';
    'DQ'<28>:
      PIN_NUMBER='(36,0,0,0)';
      BIDIRECTIONAL='TRUE';
      INPUT_LOAD='(-0.01,0.01)';
      OUTPUT_LOAD='(1.0,-1.0)';
    'DQ'<27>:
      PIN_NUMBER='(190,0,0,0)';
      BIDIRECTIONAL='TRUE';
      INPUT_LOAD='(-0.01,0.01)';
      OUTPUT_LOAD='(1.0,-1.0)';
    'DQ'<26>:
      PIN_NUMBER='(45,0,0,0)';
      BIDIRECTIONAL='TRUE';
      INPUT_LOAD='(-0.01,0.01)';
      OUTPUT_LOAD='(1.0,-1.0)';
    'DQ'<25>:
      PIN_NUMBER='(183,0,0,0)';
      BIDIRECTIONAL='TRUE';
      INPUT_LOAD='(-0.01,0.01)';
      OUTPUT_LOAD='(1.0,-1.0)';
    'DQ'<24>:
      PIN_NUMBER='(38,0,0,0)';
      BIDIRECTIONAL='TRUE';
      INPUT_LOAD='(-0.01,0.01)';
      OUTPUT_LOAD='(1.0,-1.0)';
    'DQ'<23>:
      PIN_NUMBER='(177,0,0,0)';
      BIDIRECTIONAL='TRUE';
      INPUT_LOAD='(-0.01,0.01)';
      OUTPUT_LOAD='(1.0,-1.0)';
    'DQ'<22>:
      PIN_NUMBER='(32,0,0,0)';
      BIDIRECTIONAL='TRUE';
      INPUT_LOAD='(-0.01,0.01)';
      OUTPUT_LOAD='(1.0,-1.0)';
    'DQ'<21>:
      PIN_NUMBER='(170,0,0,0)';
      BIDIRECTIONAL='TRUE';
      INPUT_LOAD='(-0.01,0.01)';
      OUTPUT_LOAD='(1.0,-1.0)';
    'DQ'<20>:
      PIN_NUMBER='(25,0,0,0)';
      BIDIRECTIONAL='TRUE';
      INPUT_LOAD='(-0.01,0.01)';
      OUTPUT_LOAD='(1.0,-1.0)';
    'DQ'<19>:
      PIN_NUMBER='(179,0,0,0)';
      BIDIRECTIONAL='TRUE';
      INPUT_LOAD='(-0.01,0.01)';
      OUTPUT_LOAD='(1.0,-1.0)';
    'DQ'<18>:
      PIN_NUMBER='(34,0,0,0)';
      BIDIRECTIONAL='TRUE';
      INPUT_LOAD='(-0.01,0.01)';
      OUTPUT_LOAD='(1.0,-1.0)';
    'DQ'<17>:
      PIN_NUMBER='(172,0,0,0)';
      BIDIRECTIONAL='TRUE';
      INPUT_LOAD='(-0.01,0.01)';
      OUTPUT_LOAD='(1.0,-1.0)';
    'DQ'<16>:
      PIN_NUMBER='(27,0,0,0)';
      BIDIRECTIONAL='TRUE';
      INPUT_LOAD='(-0.01,0.01)';
      OUTPUT_LOAD='(1.0,-1.0)';
    'DQ'<15>:
      PIN_NUMBER='(166,0,0,0)';
      BIDIRECTIONAL='TRUE';
      INPUT_LOAD='(-0.01,0.01)';
      OUTPUT_LOAD='(1.0,-1.0)';
    'DQ'<14>:
      PIN_NUMBER='(21,0,0,0)';
      BIDIRECTIONAL='TRUE';
      INPUT_LOAD='(-0.01,0.01)';
      OUTPUT_LOAD='(1.0,-1.0)';
    'DQ'<13>:
      PIN_NUMBER='(159,0,0,0)';
      BIDIRECTIONAL='TRUE';
      INPUT_LOAD='(-0.01,0.01)';
      OUTPUT_LOAD='(1.0,-1.0)';
    'DQ'<12>:
      PIN_NUMBER='(14,0,0,0)';
      BIDIRECTIONAL='TRUE';
      INPUT_LOAD='(-0.01,0.01)';
      OUTPUT_LOAD='(1.0,-1.0)';
    'DQ'<11>:
      PIN_NUMBER='(168,0,0,0)';
      BIDIRECTIONAL='TRUE';
      INPUT_LOAD='(-0.01,0.01)';
      OUTPUT_LOAD='(1.0,-1.0)';
    'DQ'<10>:
      PIN_NUMBER='(23,0,0,0)';
      BIDIRECTIONAL='TRUE';
      INPUT_LOAD='(-0.01,0.01)';
      OUTPUT_LOAD='(1.0,-1.0)';
    'DQ'<9>:
      PIN_NUMBER='(161,0,0,0)';
      BIDIRECTIONAL='TRUE';
      INPUT_LOAD='(-0.01,0.01)';
      OUTPUT_LOAD='(1.0,-1.0)';
    'DQ'<8>:
      PIN_NUMBER='(16,0,0,0)';
      BIDIRECTIONAL='TRUE';
      INPUT_LOAD='(-0.01,0.01)';
      OUTPUT_LOAD='(1.0,-1.0)';
    'DQ'<7>:
      PIN_NUMBER='(155,0,0,0)';
      BIDIRECTIONAL='TRUE';
      INPUT_LOAD='(-0.01,0.01)';
      OUTPUT_LOAD='(1.0,-1.0)';
    'DQ'<6>:
      PIN_NUMBER='(10,0,0,0)';
      BIDIRECTIONAL='TRUE';
      INPUT_LOAD='(-0.01,0.01)';
      OUTPUT_LOAD='(1.0,-1.0)';
    'DQ'<5>:
      PIN_NUMBER='(148,0,0,0)';
      BIDIRECTIONAL='TRUE';
      INPUT_LOAD='(-0.01,0.01)';
      OUTPUT_LOAD='(1.0,-1.0)';
    'DQ'<4>:
      PIN_NUMBER='(3,0,0,0)';
      BIDIRECTIONAL='TRUE';
      INPUT_LOAD='(-0.01,0.01)';
      OUTPUT_LOAD='(1.0,-1.0)';
    'DQ'<3>:
      PIN_NUMBER='(157,0,0,0)';
      BIDIRECTIONAL='TRUE';
      INPUT_LOAD='(-0.01,0.01)';
      OUTPUT_LOAD='(1.0,-1.0)';
    'DQ'<2>:
      PIN_NUMBER='(12,0,0,0)';
      BIDIRECTIONAL='TRUE';
      INPUT_LOAD='(-0.01,0.01)';
      OUTPUT_LOAD='(1.0,-1.0)';
    'DQ'<1>:
      PIN_NUMBER='(150,0,0,0)';
      BIDIRECTIONAL='TRUE';
      INPUT_LOAD='(-0.01,0.01)';
      OUTPUT_LOAD='(1.0,-1.0)';
    'DQ'<0>:
      PIN_NUMBER='(5,0,0,0)';
      BIDIRECTIONAL='TRUE';
      INPUT_LOAD='(-0.01,0.01)';
      OUTPUT_LOAD='(1.0,-1.0)';
    'DQS0N':
      PIN_NUMBER='(0,152,0,0)';
      BIDIRECTIONAL='TRUE';
      INPUT_LOAD='(-0.01,0.01)';
      OUTPUT_LOAD='(1.0,-1.0)';
    'DQS0P':
      PIN_NUMBER='(0,153,0,0)';
      BIDIRECTIONAL='TRUE';
      INPUT_LOAD='(-0.01,0.01)';
      OUTPUT_LOAD='(1.0,-1.0)';
    'DQS10N':
      PIN_NUMBER='(0,19,0,0)';
      BIDIRECTIONAL='TRUE';
      INPUT_LOAD='(-0.01,0.01)';
      OUTPUT_LOAD='(1.0,-1.0)';
    'DQS10P':
      PIN_NUMBER='(0,18,0,0)';
      BIDIRECTIONAL='TRUE';
      INPUT_LOAD='(-0.01,0.01)';
      OUTPUT_LOAD='(1.0,-1.0)';
    'DQS11N':
      PIN_NUMBER='(0,30,0,0)';
      BIDIRECTIONAL='TRUE';
      INPUT_LOAD='(-0.01,0.01)';
      OUTPUT_LOAD='(1.0,-1.0)';
    'DQS11P':
      PIN_NUMBER='(0,29,0,0)';
      BIDIRECTIONAL='TRUE';
      INPUT_LOAD='(-0.01,0.01)';
      OUTPUT_LOAD='(1.0,-1.0)';
    'DQS12N':
      PIN_NUMBER='(0,41,0,0)';
      BIDIRECTIONAL='TRUE';
      INPUT_LOAD='(-0.01,0.01)';
      OUTPUT_LOAD='(1.0,-1.0)';
    'DQS12P':
      PIN_NUMBER='(0,40,0,0)';
      BIDIRECTIONAL='TRUE';
      INPUT_LOAD='(-0.01,0.01)';
      OUTPUT_LOAD='(1.0,-1.0)';
    'DQS13N':
      PIN_NUMBER='(0,100,0,0)';
      BIDIRECTIONAL='TRUE';
      INPUT_LOAD='(-0.01,0.01)';
      OUTPUT_LOAD='(1.0,-1.0)';
    'DQS13P':
      PIN_NUMBER='(0,99,0,0)';
      BIDIRECTIONAL='TRUE';
      INPUT_LOAD='(-0.01,0.01)';
      OUTPUT_LOAD='(1.0,-1.0)';
    'DQS14N':
      PIN_NUMBER='(0,111,0,0)';
      BIDIRECTIONAL='TRUE';
      INPUT_LOAD='(-0.01,0.01)';
      OUTPUT_LOAD='(1.0,-1.0)';
    'DQS14P':
      PIN_NUMBER='(0,110,0,0)';
      BIDIRECTIONAL='TRUE';
      INPUT_LOAD='(-0.01,0.01)';
      OUTPUT_LOAD='(1.0,-1.0)';
    'DQS15N':
      PIN_NUMBER='(0,122,0,0)';
      BIDIRECTIONAL='TRUE';
      INPUT_LOAD='(-0.01,0.01)';
      OUTPUT_LOAD='(1.0,-1.0)';
    'DQS15P':
      PIN_NUMBER='(0,121,0,0)';
      BIDIRECTIONAL='TRUE';
      INPUT_LOAD='(-0.01,0.01)';
      OUTPUT_LOAD='(1.0,-1.0)';
    'DQS16N':
      PIN_NUMBER='(0,133,0,0)';
      BIDIRECTIONAL='TRUE';
      INPUT_LOAD='(-0.01,0.01)';
      OUTPUT_LOAD='(1.0,-1.0)';
    'DQS16P':
      PIN_NUMBER='(0,132,0,0)';
      BIDIRECTIONAL='TRUE';
      INPUT_LOAD='(-0.01,0.01)';
      OUTPUT_LOAD='(1.0,-1.0)';
    'DQS17N':
      PIN_NUMBER='(0,52,0,0)';
      BIDIRECTIONAL='TRUE';
      INPUT_LOAD='(-0.01,0.01)';
      OUTPUT_LOAD='(1.0,-1.0)';
    'DQS17P':
      PIN_NUMBER='(0,51,0,0)';
      BIDIRECTIONAL='TRUE';
      INPUT_LOAD='(-0.01,0.01)';
      OUTPUT_LOAD='(1.0,-1.0)';
    'DQS1N':
      PIN_NUMBER='(0,163,0,0)';
      BIDIRECTIONAL='TRUE';
      INPUT_LOAD='(-0.01,0.01)';
      OUTPUT_LOAD='(1.0,-1.0)';
    'DQS1P':
      PIN_NUMBER='(0,164,0,0)';
      BIDIRECTIONAL='TRUE';
      INPUT_LOAD='(-0.01,0.01)';
      OUTPUT_LOAD='(1.0,-1.0)';
    'DQS2N':
      PIN_NUMBER='(0,174,0,0)';
      BIDIRECTIONAL='TRUE';
      INPUT_LOAD='(-0.01,0.01)';
      OUTPUT_LOAD='(1.0,-1.0)';
    'DQS2P':
      PIN_NUMBER='(0,175,0,0)';
      BIDIRECTIONAL='TRUE';
      INPUT_LOAD='(-0.01,0.01)';
      OUTPUT_LOAD='(1.0,-1.0)';
    'DQS3N':
      PIN_NUMBER='(0,185,0,0)';
      BIDIRECTIONAL='TRUE';
      INPUT_LOAD='(-0.01,0.01)';
      OUTPUT_LOAD='(1.0,-1.0)';
    'DQS3P':
      PIN_NUMBER='(0,186,0,0)';
      BIDIRECTIONAL='TRUE';
      INPUT_LOAD='(-0.01,0.01)';
      OUTPUT_LOAD='(1.0,-1.0)';
    'DQS4N':
      PIN_NUMBER='(0,244,0,0)';
      BIDIRECTIONAL='TRUE';
      INPUT_LOAD='(-0.01,0.01)';
      OUTPUT_LOAD='(1.0,-1.0)';
    'DQS4P':
      PIN_NUMBER='(0,245,0,0)';
      BIDIRECTIONAL='TRUE';
      INPUT_LOAD='(-0.01,0.01)';
      OUTPUT_LOAD='(1.0,-1.0)';
    'DQS5N':
      PIN_NUMBER='(0,255,0,0)';
      BIDIRECTIONAL='TRUE';
      INPUT_LOAD='(-0.01,0.01)';
      OUTPUT_LOAD='(1.0,-1.0)';
    'DQS5P':
      PIN_NUMBER='(0,256,0,0)';
      BIDIRECTIONAL='TRUE';
      INPUT_LOAD='(-0.01,0.01)';
      OUTPUT_LOAD='(1.0,-1.0)';
    'DQS6N':
      PIN_NUMBER='(0,266,0,0)';
      BIDIRECTIONAL='TRUE';
      INPUT_LOAD='(-0.01,0.01)';
      OUTPUT_LOAD='(1.0,-1.0)';
    'DQS6P':
      PIN_NUMBER='(0,267,0,0)';
      BIDIRECTIONAL='TRUE';
      INPUT_LOAD='(-0.01,0.01)';
      OUTPUT_LOAD='(1.0,-1.0)';
    'DQS7N':
      PIN_NUMBER='(0,277,0,0)';
      BIDIRECTIONAL='TRUE';
      INPUT_LOAD='(-0.01,0.01)';
      OUTPUT_LOAD='(1.0,-1.0)';
    'DQS7P':
      PIN_NUMBER='(0,278,0,0)';
      BIDIRECTIONAL='TRUE';
      INPUT_LOAD='(-0.01,0.01)';
      OUTPUT_LOAD='(1.0,-1.0)';
    'DQS8N':
      PIN_NUMBER='(0,196,0,0)';
      BIDIRECTIONAL='TRUE';
      INPUT_LOAD='(-0.01,0.01)';
      OUTPUT_LOAD='(1.0,-1.0)';
    'DQS8P':
      PIN_NUMBER='(0,197,0,0)';
      BIDIRECTIONAL='TRUE';
      INPUT_LOAD='(-0.01,0.01)';
      OUTPUT_LOAD='(1.0,-1.0)';
    'DQS9N':
      PIN_NUMBER='(0,8,0,0)';
      BIDIRECTIONAL='TRUE';
      INPUT_LOAD='(-0.01,0.01)';
      OUTPUT_LOAD='(1.0,-1.0)';
    'DQS9P':
      PIN_NUMBER='(0,7,0,0)';
      BIDIRECTIONAL='TRUE';
      INPUT_LOAD='(-0.01,0.01)';
      OUTPUT_LOAD='(1.0,-1.0)';
    'EVENT_N':
      PIN_NUMBER='(78,0,0,0)';
      BIDIRECTIONAL='TRUE';
      INPUT_LOAD='(-0.01,0.01)';
      OUTPUT_LOAD='(1.0,-1.0)';
    'ODT'<1>:
      PIN_NUMBER='(91,0,0,0)';
      BIDIRECTIONAL='TRUE';
      INPUT_LOAD='(-0.01,0.01)';
      OUTPUT_LOAD='(1.0,-1.0)';
    'ODT'<0>:
      PIN_NUMBER='(87,0,0,0)';
      BIDIRECTIONAL='TRUE';
      INPUT_LOAD='(-0.01,0.01)';
      OUTPUT_LOAD='(1.0,-1.0)';
    'PAR':
      PIN_NUMBER='(222,0,0,0)';
      BIDIRECTIONAL='TRUE';
      INPUT_LOAD='(-0.01,0.01)';
      OUTPUT_LOAD='(1.0,-1.0)';
    'RESET_N':
      PIN_NUMBER='(58,0,0,0)';
      BIDIRECTIONAL='TRUE';
      INPUT_LOAD='(-0.01,0.01)';
      OUTPUT_LOAD='(1.0,-1.0)';
    'RFU'<2>:
      PIN_NUMBER='(144,0,0,0)';
      BIDIRECTIONAL='TRUE';
      INPUT_LOAD='(-0.01,0.01)';
      OUTPUT_LOAD='(1.0,-1.0)';
    'RFU'<1>:
      PIN_NUMBER='(227,0,0,0)';
      BIDIRECTIONAL='TRUE';
      INPUT_LOAD='(-0.01,0.01)';
      OUTPUT_LOAD='(1.0,-1.0)';
    'RFU'<0>:
      PIN_NUMBER='(205,0,0,0)';
      BIDIRECTIONAL='TRUE';
      INPUT_LOAD='(-0.01,0.01)';
      OUTPUT_LOAD='(1.0,-1.0)';
    'S0_N':
      PIN_NUMBER='(84,0,0,0)';
      BIDIRECTIONAL='TRUE';
      INPUT_LOAD='(-0.01,0.01)';
      OUTPUT_LOAD='(1.0,-1.0)';
    'S1_N':
      PIN_NUMBER='(89,0,0,0)';
      BIDIRECTIONAL='TRUE';
      INPUT_LOAD='(-0.01,0.01)';
      OUTPUT_LOAD='(1.0,-1.0)';
    'S2_N_C'<0>:
      PIN_NUMBER='(93,0,0,0)';
      BIDIRECTIONAL='TRUE';
      INPUT_LOAD='(-0.01,0.01)';
      OUTPUT_LOAD='(1.0,-1.0)';
    'S3_N_C'<1>:
      PIN_NUMBER='(237,0,0,0)';
      BIDIRECTIONAL='TRUE';
      INPUT_LOAD='(-0.01,0.01)';
      OUTPUT_LOAD='(1.0,-1.0)';
    'SA'<2>:
      PIN_NUMBER='(238,0,0,0)';
      BIDIRECTIONAL='TRUE';
      INPUT_LOAD='(-0.01,0.01)';
      OUTPUT_LOAD='(1.0,-1.0)';
    'SA'<1>:
      PIN_NUMBER='(140,0,0,0)';
      BIDIRECTIONAL='TRUE';
      INPUT_LOAD='(-0.01,0.01)';
      OUTPUT_LOAD='(1.0,-1.0)';
    'SA'<0>:
      PIN_NUMBER='(139,0,0,0)';
      BIDIRECTIONAL='TRUE';
      INPUT_LOAD='(-0.01,0.01)';
      OUTPUT_LOAD='(1.0,-1.0)';
    'SAVE_N_NC':
      PIN_NUMBER='(230,0,0,0)';
      BIDIRECTIONAL='TRUE';
      INPUT_LOAD='(-0.01,0.01)';
      OUTPUT_LOAD='(1.0,-1.0)';
    'SCL':
      PIN_NUMBER='(141,0,0,0)';
      BIDIRECTIONAL='TRUE';
      INPUT_LOAD='(-0.01,0.01)';
      OUTPUT_LOAD='(1.0,-1.0)';
    'SDA':
      PIN_NUMBER='(285,0,0,0)';
      BIDIRECTIONAL='TRUE';
      INPUT_LOAD='(-0.01,0.01)';
      OUTPUT_LOAD='(1.0,-1.0)';
    'VDD'<25>:
      PIN_NUMBER='(0,0,0,59)';
      PINUSE='POWER';
      NO_LOAD_CHECK='Both';
      NO_IO_CHECK='Both';
      NO_ASSERT_CHECK='TRUE';
      NO_DIR_CHECK='TRUE';
      ALLOW_CONNECT='TRUE';
    'VDD'<24>:
      PIN_NUMBER='(0,0,0,61)';
      PINUSE='POWER';
      NO_LOAD_CHECK='Both';
      NO_IO_CHECK='Both';
      NO_ASSERT_CHECK='TRUE';
      NO_DIR_CHECK='TRUE';
      ALLOW_CONNECT='TRUE';
    'VDD'<23>:
      PIN_NUMBER='(0,0,0,64)';
      PINUSE='POWER';
      NO_LOAD_CHECK='Both';
      NO_IO_CHECK='Both';
      NO_ASSERT_CHECK='TRUE';
      NO_DIR_CHECK='TRUE';
      ALLOW_CONNECT='TRUE';
    'VDD'<22>:
      PIN_NUMBER='(0,0,0,67)';
      PINUSE='POWER';
      NO_LOAD_CHECK='Both';
      NO_IO_CHECK='Both';
      NO_ASSERT_CHECK='TRUE';
      NO_DIR_CHECK='TRUE';
      ALLOW_CONNECT='TRUE';
    'VDD'<21>:
      PIN_NUMBER='(0,0,0,70)';
      PINUSE='POWER';
      NO_LOAD_CHECK='Both';
      NO_IO_CHECK='Both';
      NO_ASSERT_CHECK='TRUE';
      NO_DIR_CHECK='TRUE';
      ALLOW_CONNECT='TRUE';
    'VDD'<20>:
      PIN_NUMBER='(0,0,0,73)';
      PINUSE='POWER';
      NO_LOAD_CHECK='Both';
      NO_IO_CHECK='Both';
      NO_ASSERT_CHECK='TRUE';
      NO_DIR_CHECK='TRUE';
      ALLOW_CONNECT='TRUE';
    'VDD'<19>:
      PIN_NUMBER='(0,0,0,76)';
      PINUSE='POWER';
      NO_LOAD_CHECK='Both';
      NO_IO_CHECK='Both';
      NO_ASSERT_CHECK='TRUE';
      NO_DIR_CHECK='TRUE';
      ALLOW_CONNECT='TRUE';
    'VDD'<18>:
      PIN_NUMBER='(0,0,0,80)';
      PINUSE='POWER';
      NO_LOAD_CHECK='Both';
      NO_IO_CHECK='Both';
      NO_ASSERT_CHECK='TRUE';
      NO_DIR_CHECK='TRUE';
      ALLOW_CONNECT='TRUE';
    'VDD'<17>:
      PIN_NUMBER='(0,0,0,83)';
      PINUSE='POWER';
      NO_LOAD_CHECK='Both';
      NO_IO_CHECK='Both';
      NO_ASSERT_CHECK='TRUE';
      NO_DIR_CHECK='TRUE';
      ALLOW_CONNECT='TRUE';
    'VDD'<16>:
      PIN_NUMBER='(0,0,0,85)';
      PINUSE='POWER';
      NO_LOAD_CHECK='Both';
      NO_IO_CHECK='Both';
      NO_ASSERT_CHECK='TRUE';
      NO_DIR_CHECK='TRUE';
      ALLOW_CONNECT='TRUE';
    'VDD'<15>:
      PIN_NUMBER='(0,0,0,88)';
      PINUSE='POWER';
      NO_LOAD_CHECK='Both';
      NO_IO_CHECK='Both';
      NO_ASSERT_CHECK='TRUE';
      NO_DIR_CHECK='TRUE';
      ALLOW_CONNECT='TRUE';
    'VDD'<14>:
      PIN_NUMBER='(0,0,0,90)';
      PINUSE='POWER';
      NO_LOAD_CHECK='Both';
      NO_IO_CHECK='Both';
      NO_ASSERT_CHECK='TRUE';
      NO_DIR_CHECK='TRUE';
      ALLOW_CONNECT='TRUE';
    'VDD'<13>:
      PIN_NUMBER='(0,0,0,92)';
      PINUSE='POWER';
      NO_LOAD_CHECK='Both';
      NO_IO_CHECK='Both';
      NO_ASSERT_CHECK='TRUE';
      NO_DIR_CHECK='TRUE';
      ALLOW_CONNECT='TRUE';
    'VDD'<12>:
      PIN_NUMBER='(0,0,0,204)';
      PINUSE='POWER';
      NO_LOAD_CHECK='Both';
      NO_IO_CHECK='Both';
      NO_ASSERT_CHECK='TRUE';
      NO_DIR_CHECK='TRUE';
      ALLOW_CONNECT='TRUE';
    'VDD'<11>:
      PIN_NUMBER='(0,0,0,206)';
      PINUSE='POWER';
      NO_LOAD_CHECK='Both';
      NO_IO_CHECK='Both';
      NO_ASSERT_CHECK='TRUE';
      NO_DIR_CHECK='TRUE';
      ALLOW_CONNECT='TRUE';
    'VDD'<10>:
      PIN_NUMBER='(0,0,0,209)';
      PINUSE='POWER';
      NO_LOAD_CHECK='Both';
      NO_IO_CHECK='Both';
      NO_ASSERT_CHECK='TRUE';
      NO_DIR_CHECK='TRUE';
      ALLOW_CONNECT='TRUE';
    'VDD'<9>:
      PIN_NUMBER='(0,0,0,212)';
      PINUSE='POWER';
      NO_LOAD_CHECK='Both';
      NO_IO_CHECK='Both';
      NO_ASSERT_CHECK='TRUE';
      NO_DIR_CHECK='TRUE';
      ALLOW_CONNECT='TRUE';
    'VDD'<8>:
      PIN_NUMBER='(0,0,0,215)';
      PINUSE='POWER';
      NO_LOAD_CHECK='Both';
      NO_IO_CHECK='Both';
      NO_ASSERT_CHECK='TRUE';
      NO_DIR_CHECK='TRUE';
      ALLOW_CONNECT='TRUE';
    'VDD'<7>:
      PIN_NUMBER='(0,0,0,217)';
      PINUSE='POWER';
      NO_LOAD_CHECK='Both';
      NO_IO_CHECK='Both';
      NO_ASSERT_CHECK='TRUE';
      NO_DIR_CHECK='TRUE';
      ALLOW_CONNECT='TRUE';
    'VDD'<6>:
      PIN_NUMBER='(0,0,0,220)';
      PINUSE='POWER';
      NO_LOAD_CHECK='Both';
      NO_IO_CHECK='Both';
      NO_ASSERT_CHECK='TRUE';
      NO_DIR_CHECK='TRUE';
      ALLOW_CONNECT='TRUE';
    'VDD'<5>:
      PIN_NUMBER='(0,0,0,223)';
      PINUSE='POWER';
      NO_LOAD_CHECK='Both';
      NO_IO_CHECK='Both';
      NO_ASSERT_CHECK='TRUE';
      NO_DIR_CHECK='TRUE';
      ALLOW_CONNECT='TRUE';
    'VDD'<4>:
      PIN_NUMBER='(0,0,0,226)';
      PINUSE='POWER';
      NO_LOAD_CHECK='Both';
      NO_IO_CHECK='Both';
      NO_ASSERT_CHECK='TRUE';
      NO_DIR_CHECK='TRUE';
      ALLOW_CONNECT='TRUE';
    'VDD'<3>:
      PIN_NUMBER='(0,0,0,229)';
      PINUSE='POWER';
      NO_LOAD_CHECK='Both';
      NO_IO_CHECK='Both';
      NO_ASSERT_CHECK='TRUE';
      NO_DIR_CHECK='TRUE';
      ALLOW_CONNECT='TRUE';
    'VDD'<2>:
      PIN_NUMBER='(0,0,0,231)';
      PINUSE='POWER';
      NO_LOAD_CHECK='Both';
      NO_IO_CHECK='Both';
      NO_ASSERT_CHECK='TRUE';
      NO_DIR_CHECK='TRUE';
      ALLOW_CONNECT='TRUE';
    'VDD'<1>:
      PIN_NUMBER='(0,0,0,233)';
      PINUSE='POWER';
      NO_LOAD_CHECK='Both';
      NO_IO_CHECK='Both';
      NO_ASSERT_CHECK='TRUE';
      NO_DIR_CHECK='TRUE';
      ALLOW_CONNECT='TRUE';
    'VDD'<0>:
      PIN_NUMBER='(0,0,0,236)';
      PINUSE='POWER';
      NO_LOAD_CHECK='Both';
      NO_IO_CHECK='Both';
      NO_ASSERT_CHECK='TRUE';
      NO_DIR_CHECK='TRUE';
      ALLOW_CONNECT='TRUE';
    'VDDSPD':
      PIN_NUMBER='(284,0,0,0)';
      BIDIRECTIONAL='TRUE';
      INPUT_LOAD='(-0.01,0.01)';
      OUTPUT_LOAD='(1.0,-1.0)';
    'VPP'<4>:
      PIN_NUMBER='(0,0,0,142)';
      PINUSE='POWER';
      NO_LOAD_CHECK='Both';
      NO_IO_CHECK='Both';
      NO_ASSERT_CHECK='TRUE';
      NO_DIR_CHECK='TRUE';
      ALLOW_CONNECT='TRUE';
    'VPP'<3>:
      PIN_NUMBER='(0,0,0,143)';
      PINUSE='POWER';
      NO_LOAD_CHECK='Both';
      NO_IO_CHECK='Both';
      NO_ASSERT_CHECK='TRUE';
      NO_DIR_CHECK='TRUE';
      ALLOW_CONNECT='TRUE';
    'VPP'<2>:
      PIN_NUMBER='(0,0,0,288)';
      PINUSE='POWER';
      NO_LOAD_CHECK='Both';
      NO_IO_CHECK='Both';
      NO_ASSERT_CHECK='TRUE';
      NO_DIR_CHECK='TRUE';
      ALLOW_CONNECT='TRUE';
    'VPP'<1>:
      PIN_NUMBER='(0,0,0,286)';
      PINUSE='POWER';
      NO_LOAD_CHECK='Both';
      NO_IO_CHECK='Both';
      NO_ASSERT_CHECK='TRUE';
      NO_DIR_CHECK='TRUE';
      ALLOW_CONNECT='TRUE';
    'VPP'<0>:
      PIN_NUMBER='(0,0,0,287)';
      PINUSE='POWER';
      NO_LOAD_CHECK='Both';
      NO_IO_CHECK='Both';
      NO_ASSERT_CHECK='TRUE';
      NO_DIR_CHECK='TRUE';
      ALLOW_CONNECT='TRUE';
    'VREFCA':
      PIN_NUMBER='(146,0,0,0)';
      BIDIRECTIONAL='TRUE';
      INPUT_LOAD='(-0.01,0.01)';
      OUTPUT_LOAD='(1.0,-1.0)';
    'VSS'<93>:
      PIN_NUMBER='(0,0,2,0)';
      PINUSE='GROUND';
      NO_LOAD_CHECK='Both';
      NO_IO_CHECK='Both';
      NO_ASSERT_CHECK='TRUE';
      NO_DIR_CHECK='TRUE';
      ALLOW_CONNECT='TRUE';
    'VSS'<92>:
      PIN_NUMBER='(0,0,4,0)';
      PINUSE='GROUND';
      NO_LOAD_CHECK='Both';
      NO_IO_CHECK='Both';
      NO_ASSERT_CHECK='TRUE';
      NO_DIR_CHECK='TRUE';
      ALLOW_CONNECT='TRUE';
    'VSS'<91>:
      PIN_NUMBER='(0,0,6,0)';
      PINUSE='GROUND';
      NO_LOAD_CHECK='Both';
      NO_IO_CHECK='Both';
      NO_ASSERT_CHECK='TRUE';
      NO_DIR_CHECK='TRUE';
      ALLOW_CONNECT='TRUE';
    'VSS'<90>:
      PIN_NUMBER='(0,0,9,0)';
      PINUSE='GROUND';
      NO_LOAD_CHECK='Both';
      NO_IO_CHECK='Both';
      NO_ASSERT_CHECK='TRUE';
      NO_DIR_CHECK='TRUE';
      ALLOW_CONNECT='TRUE';
    'VSS'<89>:
      PIN_NUMBER='(0,0,11,0)';
      PINUSE='GROUND';
      NO_LOAD_CHECK='Both';
      NO_IO_CHECK='Both';
      NO_ASSERT_CHECK='TRUE';
      NO_DIR_CHECK='TRUE';
      ALLOW_CONNECT='TRUE';
    'VSS'<88>:
      PIN_NUMBER='(0,0,13,0)';
      PINUSE='GROUND';
      NO_LOAD_CHECK='Both';
      NO_IO_CHECK='Both';
      NO_ASSERT_CHECK='TRUE';
      NO_DIR_CHECK='TRUE';
      ALLOW_CONNECT='TRUE';
    'VSS'<87>:
      PIN_NUMBER='(0,0,15,0)';
      PINUSE='GROUND';
      NO_LOAD_CHECK='Both';
      NO_IO_CHECK='Both';
      NO_ASSERT_CHECK='TRUE';
      NO_DIR_CHECK='TRUE';
      ALLOW_CONNECT='TRUE';
    'VSS'<86>:
      PIN_NUMBER='(0,0,17,0)';
      PINUSE='GROUND';
      NO_LOAD_CHECK='Both';
      NO_IO_CHECK='Both';
      NO_ASSERT_CHECK='TRUE';
      NO_DIR_CHECK='TRUE';
      ALLOW_CONNECT='TRUE';
    'VSS'<85>:
      PIN_NUMBER='(0,0,20,0)';
      PINUSE='GROUND';
      NO_LOAD_CHECK='Both';
      NO_IO_CHECK='Both';
      NO_ASSERT_CHECK='TRUE';
      NO_DIR_CHECK='TRUE';
      ALLOW_CONNECT='TRUE';
    'VSS'<84>:
      PIN_NUMBER='(0,0,22,0)';
      PINUSE='GROUND';
      NO_LOAD_CHECK='Both';
      NO_IO_CHECK='Both';
      NO_ASSERT_CHECK='TRUE';
      NO_DIR_CHECK='TRUE';
      ALLOW_CONNECT='TRUE';
    'VSS'<83>:
      PIN_NUMBER='(0,0,24,0)';
      PINUSE='GROUND';
      NO_LOAD_CHECK='Both';
      NO_IO_CHECK='Both';
      NO_ASSERT_CHECK='TRUE';
      NO_DIR_CHECK='TRUE';
      ALLOW_CONNECT='TRUE';
    'VSS'<82>:
      PIN_NUMBER='(0,0,26,0)';
      PINUSE='GROUND';
      NO_LOAD_CHECK='Both';
      NO_IO_CHECK='Both';
      NO_ASSERT_CHECK='TRUE';
      NO_DIR_CHECK='TRUE';
      ALLOW_CONNECT='TRUE';
    'VSS'<81>:
      PIN_NUMBER='(0,0,28,0)';
      PINUSE='GROUND';
      NO_LOAD_CHECK='Both';
      NO_IO_CHECK='Both';
      NO_ASSERT_CHECK='TRUE';
      NO_DIR_CHECK='TRUE';
      ALLOW_CONNECT='TRUE';
    'VSS'<80>:
      PIN_NUMBER='(0,0,31,0)';
      PINUSE='GROUND';
      NO_LOAD_CHECK='Both';
      NO_IO_CHECK='Both';
      NO_ASSERT_CHECK='TRUE';
      NO_DIR_CHECK='TRUE';
      ALLOW_CONNECT='TRUE';
    'VSS'<79>:
      PIN_NUMBER='(0,0,33,0)';
      PINUSE='GROUND';
      NO_LOAD_CHECK='Both';
      NO_IO_CHECK='Both';
      NO_ASSERT_CHECK='TRUE';
      NO_DIR_CHECK='TRUE';
      ALLOW_CONNECT='TRUE';
    'VSS'<78>:
      PIN_NUMBER='(0,0,35,0)';
      PINUSE='GROUND';
      NO_LOAD_CHECK='Both';
      NO_IO_CHECK='Both';
      NO_ASSERT_CHECK='TRUE';
      NO_DIR_CHECK='TRUE';
      ALLOW_CONNECT='TRUE';
    'VSS'<77>:
      PIN_NUMBER='(0,0,37,0)';
      PINUSE='GROUND';
      NO_LOAD_CHECK='Both';
      NO_IO_CHECK='Both';
      NO_ASSERT_CHECK='TRUE';
      NO_DIR_CHECK='TRUE';
      ALLOW_CONNECT='TRUE';
    'VSS'<76>:
      PIN_NUMBER='(0,0,39,0)';
      PINUSE='GROUND';
      NO_LOAD_CHECK='Both';
      NO_IO_CHECK='Both';
      NO_ASSERT_CHECK='TRUE';
      NO_DIR_CHECK='TRUE';
      ALLOW_CONNECT='TRUE';
    'VSS'<75>:
      PIN_NUMBER='(0,0,42,0)';
      PINUSE='GROUND';
      NO_LOAD_CHECK='Both';
      NO_IO_CHECK='Both';
      NO_ASSERT_CHECK='TRUE';
      NO_DIR_CHECK='TRUE';
      ALLOW_CONNECT='TRUE';
    'VSS'<74>:
      PIN_NUMBER='(0,0,44,0)';
      PINUSE='GROUND';
      NO_LOAD_CHECK='Both';
      NO_IO_CHECK='Both';
      NO_ASSERT_CHECK='TRUE';
      NO_DIR_CHECK='TRUE';
      ALLOW_CONNECT='TRUE';
    'VSS'<73>:
      PIN_NUMBER='(0,0,46,0)';
      PINUSE='GROUND';
      NO_LOAD_CHECK='Both';
      NO_IO_CHECK='Both';
      NO_ASSERT_CHECK='TRUE';
      NO_DIR_CHECK='TRUE';
      ALLOW_CONNECT='TRUE';
    'VSS'<72>:
      PIN_NUMBER='(0,0,48,0)';
      PINUSE='GROUND';
      NO_LOAD_CHECK='Both';
      NO_IO_CHECK='Both';
      NO_ASSERT_CHECK='TRUE';
      NO_DIR_CHECK='TRUE';
      ALLOW_CONNECT='TRUE';
    'VSS'<71>:
      PIN_NUMBER='(0,0,50,0)';
      PINUSE='GROUND';
      NO_LOAD_CHECK='Both';
      NO_IO_CHECK='Both';
      NO_ASSERT_CHECK='TRUE';
      NO_DIR_CHECK='TRUE';
      ALLOW_CONNECT='TRUE';
    'VSS'<70>:
      PIN_NUMBER='(0,0,53,0)';
      PINUSE='GROUND';
      NO_LOAD_CHECK='Both';
      NO_IO_CHECK='Both';
      NO_ASSERT_CHECK='TRUE';
      NO_DIR_CHECK='TRUE';
      ALLOW_CONNECT='TRUE';
    'VSS'<69>:
      PIN_NUMBER='(0,0,55,0)';
      PINUSE='GROUND';
      NO_LOAD_CHECK='Both';
      NO_IO_CHECK='Both';
      NO_ASSERT_CHECK='TRUE';
      NO_DIR_CHECK='TRUE';
      ALLOW_CONNECT='TRUE';
    'VSS'<68>:
      PIN_NUMBER='(0,0,57,0)';
      PINUSE='GROUND';
      NO_LOAD_CHECK='Both';
      NO_IO_CHECK='Both';
      NO_ASSERT_CHECK='TRUE';
      NO_DIR_CHECK='TRUE';
      ALLOW_CONNECT='TRUE';
    'VSS'<67>:
      PIN_NUMBER='(0,0,94,0)';
      PINUSE='GROUND';
      NO_LOAD_CHECK='Both';
      NO_IO_CHECK='Both';
      NO_ASSERT_CHECK='TRUE';
      NO_DIR_CHECK='TRUE';
      ALLOW_CONNECT='TRUE';
    'VSS'<66>:
      PIN_NUMBER='(0,0,96,0)';
      PINUSE='GROUND';
      NO_LOAD_CHECK='Both';
      NO_IO_CHECK='Both';
      NO_ASSERT_CHECK='TRUE';
      NO_DIR_CHECK='TRUE';
      ALLOW_CONNECT='TRUE';
    'VSS'<65>:
      PIN_NUMBER='(0,0,98,0)';
      PINUSE='GROUND';
      NO_LOAD_CHECK='Both';
      NO_IO_CHECK='Both';
      NO_ASSERT_CHECK='TRUE';
      NO_DIR_CHECK='TRUE';
      ALLOW_CONNECT='TRUE';
    'VSS'<64>:
      PIN_NUMBER='(0,0,101,0)';
      PINUSE='GROUND';
      NO_LOAD_CHECK='Both';
      NO_IO_CHECK='Both';
      NO_ASSERT_CHECK='TRUE';
      NO_DIR_CHECK='TRUE';
      ALLOW_CONNECT='TRUE';
    'VSS'<63>:
      PIN_NUMBER='(0,0,103,0)';
      PINUSE='GROUND';
      NO_LOAD_CHECK='Both';
      NO_IO_CHECK='Both';
      NO_ASSERT_CHECK='TRUE';
      NO_DIR_CHECK='TRUE';
      ALLOW_CONNECT='TRUE';
    'VSS'<62>:
      PIN_NUMBER='(0,0,105,0)';
      PINUSE='GROUND';
      NO_LOAD_CHECK='Both';
      NO_IO_CHECK='Both';
      NO_ASSERT_CHECK='TRUE';
      NO_DIR_CHECK='TRUE';
      ALLOW_CONNECT='TRUE';
    'VSS'<61>:
      PIN_NUMBER='(0,0,107,0)';
      PINUSE='GROUND';
      NO_LOAD_CHECK='Both';
      NO_IO_CHECK='Both';
      NO_ASSERT_CHECK='TRUE';
      NO_DIR_CHECK='TRUE';
      ALLOW_CONNECT='TRUE';
    'VSS'<60>:
      PIN_NUMBER='(0,0,109,0)';
      PINUSE='GROUND';
      NO_LOAD_CHECK='Both';
      NO_IO_CHECK='Both';
      NO_ASSERT_CHECK='TRUE';
      NO_DIR_CHECK='TRUE';
      ALLOW_CONNECT='TRUE';
    'VSS'<59>:
      PIN_NUMBER='(0,0,112,0)';
      PINUSE='GROUND';
      NO_LOAD_CHECK='Both';
      NO_IO_CHECK='Both';
      NO_ASSERT_CHECK='TRUE';
      NO_DIR_CHECK='TRUE';
      ALLOW_CONNECT='TRUE';
    'VSS'<58>:
      PIN_NUMBER='(0,0,114,0)';
      PINUSE='GROUND';
      NO_LOAD_CHECK='Both';
      NO_IO_CHECK='Both';
      NO_ASSERT_CHECK='TRUE';
      NO_DIR_CHECK='TRUE';
      ALLOW_CONNECT='TRUE';
    'VSS'<57>:
      PIN_NUMBER='(0,0,116,0)';
      PINUSE='GROUND';
      NO_LOAD_CHECK='Both';
      NO_IO_CHECK='Both';
      NO_ASSERT_CHECK='TRUE';
      NO_DIR_CHECK='TRUE';
      ALLOW_CONNECT='TRUE';
    'VSS'<56>:
      PIN_NUMBER='(0,0,118,0)';
      PINUSE='GROUND';
      NO_LOAD_CHECK='Both';
      NO_IO_CHECK='Both';
      NO_ASSERT_CHECK='TRUE';
      NO_DIR_CHECK='TRUE';
      ALLOW_CONNECT='TRUE';
    'VSS'<55>:
      PIN_NUMBER='(0,0,120,0)';
      PINUSE='GROUND';
      NO_LOAD_CHECK='Both';
      NO_IO_CHECK='Both';
      NO_ASSERT_CHECK='TRUE';
      NO_DIR_CHECK='TRUE';
      ALLOW_CONNECT='TRUE';
    'VSS'<54>:
      PIN_NUMBER='(0,0,123,0)';
      PINUSE='GROUND';
      NO_LOAD_CHECK='Both';
      NO_IO_CHECK='Both';
      NO_ASSERT_CHECK='TRUE';
      NO_DIR_CHECK='TRUE';
      ALLOW_CONNECT='TRUE';
    'VSS'<53>:
      PIN_NUMBER='(0,0,125,0)';
      PINUSE='GROUND';
      NO_LOAD_CHECK='Both';
      NO_IO_CHECK='Both';
      NO_ASSERT_CHECK='TRUE';
      NO_DIR_CHECK='TRUE';
      ALLOW_CONNECT='TRUE';
    'VSS'<52>:
      PIN_NUMBER='(0,0,127,0)';
      PINUSE='GROUND';
      NO_LOAD_CHECK='Both';
      NO_IO_CHECK='Both';
      NO_ASSERT_CHECK='TRUE';
      NO_DIR_CHECK='TRUE';
      ALLOW_CONNECT='TRUE';
    'VSS'<51>:
      PIN_NUMBER='(0,0,129,0)';
      PINUSE='GROUND';
      NO_LOAD_CHECK='Both';
      NO_IO_CHECK='Both';
      NO_ASSERT_CHECK='TRUE';
      NO_DIR_CHECK='TRUE';
      ALLOW_CONNECT='TRUE';
    'VSS'<50>:
      PIN_NUMBER='(0,0,131,0)';
      PINUSE='GROUND';
      NO_LOAD_CHECK='Both';
      NO_IO_CHECK='Both';
      NO_ASSERT_CHECK='TRUE';
      NO_DIR_CHECK='TRUE';
      ALLOW_CONNECT='TRUE';
    'VSS'<49>:
      PIN_NUMBER='(0,0,134,0)';
      PINUSE='GROUND';
      NO_LOAD_CHECK='Both';
      NO_IO_CHECK='Both';
      NO_ASSERT_CHECK='TRUE';
      NO_DIR_CHECK='TRUE';
      ALLOW_CONNECT='TRUE';
    'VSS'<48>:
      PIN_NUMBER='(0,0,136,0)';
      PINUSE='GROUND';
      NO_LOAD_CHECK='Both';
      NO_IO_CHECK='Both';
      NO_ASSERT_CHECK='TRUE';
      NO_DIR_CHECK='TRUE';
      ALLOW_CONNECT='TRUE';
    'VSS'<47>:
      PIN_NUMBER='(0,0,138,0)';
      PINUSE='GROUND';
      NO_LOAD_CHECK='Both';
      NO_IO_CHECK='Both';
      NO_ASSERT_CHECK='TRUE';
      NO_DIR_CHECK='TRUE';
      ALLOW_CONNECT='TRUE';
    'VSS'<46>:
      PIN_NUMBER='(0,0,147,0)';
      PINUSE='GROUND';
      NO_LOAD_CHECK='Both';
      NO_IO_CHECK='Both';
      NO_ASSERT_CHECK='TRUE';
      NO_DIR_CHECK='TRUE';
      ALLOW_CONNECT='TRUE';
    'VSS'<45>:
      PIN_NUMBER='(0,0,149,0)';
      PINUSE='GROUND';
      NO_LOAD_CHECK='Both';
      NO_IO_CHECK='Both';
      NO_ASSERT_CHECK='TRUE';
      NO_DIR_CHECK='TRUE';
      ALLOW_CONNECT='TRUE';
    'VSS'<44>:
      PIN_NUMBER='(0,0,151,0)';
      PINUSE='GROUND';
      NO_LOAD_CHECK='Both';
      NO_IO_CHECK='Both';
      NO_ASSERT_CHECK='TRUE';
      NO_DIR_CHECK='TRUE';
      ALLOW_CONNECT='TRUE';
    'VSS'<43>:
      PIN_NUMBER='(0,0,154,0)';
      PINUSE='GROUND';
      NO_LOAD_CHECK='Both';
      NO_IO_CHECK='Both';
      NO_ASSERT_CHECK='TRUE';
      NO_DIR_CHECK='TRUE';
      ALLOW_CONNECT='TRUE';
    'VSS'<42>:
      PIN_NUMBER='(0,0,156,0)';
      PINUSE='GROUND';
      NO_LOAD_CHECK='Both';
      NO_IO_CHECK='Both';
      NO_ASSERT_CHECK='TRUE';
      NO_DIR_CHECK='TRUE';
      ALLOW_CONNECT='TRUE';
    'VSS'<41>:
      PIN_NUMBER='(0,0,158,0)';
      PINUSE='GROUND';
      NO_LOAD_CHECK='Both';
      NO_IO_CHECK='Both';
      NO_ASSERT_CHECK='TRUE';
      NO_DIR_CHECK='TRUE';
      ALLOW_CONNECT='TRUE';
    'VSS'<40>:
      PIN_NUMBER='(0,0,160,0)';
      PINUSE='GROUND';
      NO_LOAD_CHECK='Both';
      NO_IO_CHECK='Both';
      NO_ASSERT_CHECK='TRUE';
      NO_DIR_CHECK='TRUE';
      ALLOW_CONNECT='TRUE';
    'VSS'<39>:
      PIN_NUMBER='(0,0,162,0)';
      PINUSE='GROUND';
      NO_LOAD_CHECK='Both';
      NO_IO_CHECK='Both';
      NO_ASSERT_CHECK='TRUE';
      NO_DIR_CHECK='TRUE';
      ALLOW_CONNECT='TRUE';
    'VSS'<38>:
      PIN_NUMBER='(0,0,165,0)';
      PINUSE='GROUND';
      NO_LOAD_CHECK='Both';
      NO_IO_CHECK='Both';
      NO_ASSERT_CHECK='TRUE';
      NO_DIR_CHECK='TRUE';
      ALLOW_CONNECT='TRUE';
    'VSS'<37>:
      PIN_NUMBER='(0,0,167,0)';
      PINUSE='GROUND';
      NO_LOAD_CHECK='Both';
      NO_IO_CHECK='Both';
      NO_ASSERT_CHECK='TRUE';
      NO_DIR_CHECK='TRUE';
      ALLOW_CONNECT='TRUE';
    'VSS'<36>:
      PIN_NUMBER='(0,0,169,0)';
      PINUSE='GROUND';
      NO_LOAD_CHECK='Both';
      NO_IO_CHECK='Both';
      NO_ASSERT_CHECK='TRUE';
      NO_DIR_CHECK='TRUE';
      ALLOW_CONNECT='TRUE';
    'VSS'<35>:
      PIN_NUMBER='(0,0,171,0)';
      PINUSE='GROUND';
      NO_LOAD_CHECK='Both';
      NO_IO_CHECK='Both';
      NO_ASSERT_CHECK='TRUE';
      NO_DIR_CHECK='TRUE';
      ALLOW_CONNECT='TRUE';
    'VSS'<34>:
      PIN_NUMBER='(0,0,173,0)';
      PINUSE='GROUND';
      NO_LOAD_CHECK='Both';
      NO_IO_CHECK='Both';
      NO_ASSERT_CHECK='TRUE';
      NO_DIR_CHECK='TRUE';
      ALLOW_CONNECT='TRUE';
    'VSS'<33>:
      PIN_NUMBER='(0,0,176,0)';
      PINUSE='GROUND';
      NO_LOAD_CHECK='Both';
      NO_IO_CHECK='Both';
      NO_ASSERT_CHECK='TRUE';
      NO_DIR_CHECK='TRUE';
      ALLOW_CONNECT='TRUE';
    'VSS'<32>:
      PIN_NUMBER='(0,0,178,0)';
      PINUSE='GROUND';
      NO_LOAD_CHECK='Both';
      NO_IO_CHECK='Both';
      NO_ASSERT_CHECK='TRUE';
      NO_DIR_CHECK='TRUE';
      ALLOW_CONNECT='TRUE';
    'VSS'<31>:
      PIN_NUMBER='(0,0,180,0)';
      PINUSE='GROUND';
      NO_LOAD_CHECK='Both';
      NO_IO_CHECK='Both';
      NO_ASSERT_CHECK='TRUE';
      NO_DIR_CHECK='TRUE';
      ALLOW_CONNECT='TRUE';
    'VSS'<30>:
      PIN_NUMBER='(0,0,182,0)';
      PINUSE='GROUND';
      NO_LOAD_CHECK='Both';
      NO_IO_CHECK='Both';
      NO_ASSERT_CHECK='TRUE';
      NO_DIR_CHECK='TRUE';
      ALLOW_CONNECT='TRUE';
    'VSS'<29>:
      PIN_NUMBER='(0,0,184,0)';
      PINUSE='GROUND';
      NO_LOAD_CHECK='Both';
      NO_IO_CHECK='Both';
      NO_ASSERT_CHECK='TRUE';
      NO_DIR_CHECK='TRUE';
      ALLOW_CONNECT='TRUE';
    'VSS'<28>:
      PIN_NUMBER='(0,0,187,0)';
      PINUSE='GROUND';
      NO_LOAD_CHECK='Both';
      NO_IO_CHECK='Both';
      NO_ASSERT_CHECK='TRUE';
      NO_DIR_CHECK='TRUE';
      ALLOW_CONNECT='TRUE';
    'VSS'<27>:
      PIN_NUMBER='(0,0,189,0)';
      PINUSE='GROUND';
      NO_LOAD_CHECK='Both';
      NO_IO_CHECK='Both';
      NO_ASSERT_CHECK='TRUE';
      NO_DIR_CHECK='TRUE';
      ALLOW_CONNECT='TRUE';
    'VSS'<26>:
      PIN_NUMBER='(0,0,191,0)';
      PINUSE='GROUND';
      NO_LOAD_CHECK='Both';
      NO_IO_CHECK='Both';
      NO_ASSERT_CHECK='TRUE';
      NO_DIR_CHECK='TRUE';
      ALLOW_CONNECT='TRUE';
    'VSS'<25>:
      PIN_NUMBER='(0,0,193,0)';
      PINUSE='GROUND';
      NO_LOAD_CHECK='Both';
      NO_IO_CHECK='Both';
      NO_ASSERT_CHECK='TRUE';
      NO_DIR_CHECK='TRUE';
      ALLOW_CONNECT='TRUE';
    'VSS'<24>:
      PIN_NUMBER='(0,0,195,0)';
      PINUSE='GROUND';
      NO_LOAD_CHECK='Both';
      NO_IO_CHECK='Both';
      NO_ASSERT_CHECK='TRUE';
      NO_DIR_CHECK='TRUE';
      ALLOW_CONNECT='TRUE';
    'VSS'<23>:
      PIN_NUMBER='(0,0,198,0)';
      PINUSE='GROUND';
      NO_LOAD_CHECK='Both';
      NO_IO_CHECK='Both';
      NO_ASSERT_CHECK='TRUE';
      NO_DIR_CHECK='TRUE';
      ALLOW_CONNECT='TRUE';
    'VSS'<22>:
      PIN_NUMBER='(0,0,200,0)';
      PINUSE='GROUND';
      NO_LOAD_CHECK='Both';
      NO_IO_CHECK='Both';
      NO_ASSERT_CHECK='TRUE';
      NO_DIR_CHECK='TRUE';
      ALLOW_CONNECT='TRUE';
    'VSS'<21>:
      PIN_NUMBER='(0,0,202,0)';
      PINUSE='GROUND';
      NO_LOAD_CHECK='Both';
      NO_IO_CHECK='Both';
      NO_ASSERT_CHECK='TRUE';
      NO_DIR_CHECK='TRUE';
      ALLOW_CONNECT='TRUE';
    'VSS'<20>:
      PIN_NUMBER='(0,0,239,0)';
      PINUSE='GROUND';
      NO_LOAD_CHECK='Both';
      NO_IO_CHECK='Both';
      NO_ASSERT_CHECK='TRUE';
      NO_DIR_CHECK='TRUE';
      ALLOW_CONNECT='TRUE';
    'VSS'<19>:
      PIN_NUMBER='(0,0,241,0)';
      PINUSE='GROUND';
      NO_LOAD_CHECK='Both';
      NO_IO_CHECK='Both';
      NO_ASSERT_CHECK='TRUE';
      NO_DIR_CHECK='TRUE';
      ALLOW_CONNECT='TRUE';
    'VSS'<18>:
      PIN_NUMBER='(0,0,243,0)';
      PINUSE='GROUND';
      NO_LOAD_CHECK='Both';
      NO_IO_CHECK='Both';
      NO_ASSERT_CHECK='TRUE';
      NO_DIR_CHECK='TRUE';
      ALLOW_CONNECT='TRUE';
    'VSS'<17>:
      PIN_NUMBER='(0,0,246,0)';
      PINUSE='GROUND';
      NO_LOAD_CHECK='Both';
      NO_IO_CHECK='Both';
      NO_ASSERT_CHECK='TRUE';
      NO_DIR_CHECK='TRUE';
      ALLOW_CONNECT='TRUE';
    'VSS'<16>:
      PIN_NUMBER='(0,0,248,0)';
      PINUSE='GROUND';
      NO_LOAD_CHECK='Both';
      NO_IO_CHECK='Both';
      NO_ASSERT_CHECK='TRUE';
      NO_DIR_CHECK='TRUE';
      ALLOW_CONNECT='TRUE';
    'VSS'<15>:
      PIN_NUMBER='(0,0,250,0)';
      PINUSE='GROUND';
      NO_LOAD_CHECK='Both';
      NO_IO_CHECK='Both';
      NO_ASSERT_CHECK='TRUE';
      NO_DIR_CHECK='TRUE';
      ALLOW_CONNECT='TRUE';
    'VSS'<14>:
      PIN_NUMBER='(0,0,252,0)';
      PINUSE='GROUND';
      NO_LOAD_CHECK='Both';
      NO_IO_CHECK='Both';
      NO_ASSERT_CHECK='TRUE';
      NO_DIR_CHECK='TRUE';
      ALLOW_CONNECT='TRUE';
    'VSS'<13>:
      PIN_NUMBER='(0,0,254,0)';
      PINUSE='GROUND';
      NO_LOAD_CHECK='Both';
      NO_IO_CHECK='Both';
      NO_ASSERT_CHECK='TRUE';
      NO_DIR_CHECK='TRUE';
      ALLOW_CONNECT='TRUE';
    'VSS'<12>:
      PIN_NUMBER='(0,0,257,0)';
      PINUSE='GROUND';
      NO_LOAD_CHECK='Both';
      NO_IO_CHECK='Both';
      NO_ASSERT_CHECK='TRUE';
      NO_DIR_CHECK='TRUE';
      ALLOW_CONNECT='TRUE';
    'VSS'<11>:
      PIN_NUMBER='(0,0,259,0)';
      PINUSE='GROUND';
      NO_LOAD_CHECK='Both';
      NO_IO_CHECK='Both';
      NO_ASSERT_CHECK='TRUE';
      NO_DIR_CHECK='TRUE';
      ALLOW_CONNECT='TRUE';
    'VSS'<10>:
      PIN_NUMBER='(0,0,261,0)';
      PINUSE='GROUND';
      NO_LOAD_CHECK='Both';
      NO_IO_CHECK='Both';
      NO_ASSERT_CHECK='TRUE';
      NO_DIR_CHECK='TRUE';
      ALLOW_CONNECT='TRUE';
    'VSS'<9>:
      PIN_NUMBER='(0,0,263,0)';
      PINUSE='GROUND';
      NO_LOAD_CHECK='Both';
      NO_IO_CHECK='Both';
      NO_ASSERT_CHECK='TRUE';
      NO_DIR_CHECK='TRUE';
      ALLOW_CONNECT='TRUE';
    'VSS'<8>:
      PIN_NUMBER='(0,0,265,0)';
      PINUSE='GROUND';
      NO_LOAD_CHECK='Both';
      NO_IO_CHECK='Both';
      NO_ASSERT_CHECK='TRUE';
      NO_DIR_CHECK='TRUE';
      ALLOW_CONNECT='TRUE';
    'VSS'<7>:
      PIN_NUMBER='(0,0,268,0)';
      PINUSE='GROUND';
      NO_LOAD_CHECK='Both';
      NO_IO_CHECK='Both';
      NO_ASSERT_CHECK='TRUE';
      NO_DIR_CHECK='TRUE';
      ALLOW_CONNECT='TRUE';
    'VSS'<6>:
      PIN_NUMBER='(0,0,270,0)';
      PINUSE='GROUND';
      NO_LOAD_CHECK='Both';
      NO_IO_CHECK='Both';
      NO_ASSERT_CHECK='TRUE';
      NO_DIR_CHECK='TRUE';
      ALLOW_CONNECT='TRUE';
    'VSS'<5>:
      PIN_NUMBER='(0,0,272,0)';
      PINUSE='GROUND';
      NO_LOAD_CHECK='Both';
      NO_IO_CHECK='Both';
      NO_ASSERT_CHECK='TRUE';
      NO_DIR_CHECK='TRUE';
      ALLOW_CONNECT='TRUE';
    'VSS'<4>:
      PIN_NUMBER='(0,0,274,0)';
      PINUSE='GROUND';
      NO_LOAD_CHECK='Both';
      NO_IO_CHECK='Both';
      NO_ASSERT_CHECK='TRUE';
      NO_DIR_CHECK='TRUE';
      ALLOW_CONNECT='TRUE';
    'VSS'<3>:
      PIN_NUMBER='(0,0,276,0)';
      PINUSE='GROUND';
      NO_LOAD_CHECK='Both';
      NO_IO_CHECK='Both';
      NO_ASSERT_CHECK='TRUE';
      NO_DIR_CHECK='TRUE';
      ALLOW_CONNECT='TRUE';
    'VSS'<2>:
      PIN_NUMBER='(0,0,279,0)';
      PINUSE='GROUND';
      NO_LOAD_CHECK='Both';
      NO_IO_CHECK='Both';
      NO_ASSERT_CHECK='TRUE';
      NO_DIR_CHECK='TRUE';
      ALLOW_CONNECT='TRUE';
    'VSS'<1>:
      PIN_NUMBER='(0,0,281,0)';
      PINUSE='GROUND';
      NO_LOAD_CHECK='Both';
      NO_IO_CHECK='Both';
      NO_ASSERT_CHECK='TRUE';
      NO_DIR_CHECK='TRUE';
      ALLOW_CONNECT='TRUE';
    'VSS'<0>:
      PIN_NUMBER='(0,0,283,0)';
      PINUSE='GROUND';
      NO_LOAD_CHECK='Both';
      NO_IO_CHECK='Both';
      NO_ASSERT_CHECK='TRUE';
      NO_DIR_CHECK='TRUE';
      ALLOW_CONNECT='TRUE';
    'VTT'<1>:
      PIN_NUMBER='(0,0,0,77)';
      PINUSE='POWER';
      NO_LOAD_CHECK='Both';
      NO_IO_CHECK='Both';
      NO_ASSERT_CHECK='TRUE';
      NO_DIR_CHECK='TRUE';
      ALLOW_CONNECT='TRUE';
    'VTT'<0>:
      PIN_NUMBER='(0,0,0,221)';
      PINUSE='POWER';
      NO_LOAD_CHECK='Both';
      NO_IO_CHECK='Both';
      NO_ASSERT_CHECK='TRUE';
      NO_DIR_CHECK='TRUE';
      ALLOW_CONNECT='TRUE';
  end_pin;
  body
    PART_NAME='SCONN288_H44441004';
    PHYS_DES_PREFIX='J';
  end_body;
end_primitive;

END.
